# T6G (Grand Teton) — schematic netlist excerpt (pin names and nets, part order shuffled) for the footprints in the layout excerpt that follows; sources: Cadence DE-HDL packaged netlist, KiCad conversion of 04192023_DAF0TMB3IC0_F0TG_MB_C_brd_V02_OCP.brd

PR259  Q_RES  5.6 1% CHIP  pkg 0402LF  page 218 : A = SW_PVDDCR_CPU1_P1_BOOT2 ; B = SW_PVDDCR_CPU1_P1_BOOT2_R

Q106  MOSFET_NCH_DUAL  PJT138K IC  pkg SOT363XD  page 126
  S1  = GND
  G1  = GPU_WP_HW_CTRL_N
  D2  = GPU_WP_HW_CTRL_ISO_N
  S2  = GND
  G2  = GPU_WP_HW_CTRL_ISO
  D1  = GPU_WP_HW_CTRL_ISO

C6660  Q_CAP_DIFFBUS  DIFF BUS_0.22UF 6.3V 20% X6S  pkg C0201  page 319 : \1\ = P5E_CPU1_P0_TX_BUF_C_DN<15> ; \2\ = P5E_CPU1_P0_TX_BUF_DN<15>

(kicad_pcb
	(version 20260206)
	(generator "pcbnew")
	(generator_version "10.0")
	(general
		(thickness 1.6)
		(legacy_teardrops no)
	)
	(paper "A4")
	(title_block
		(title "04192023_DAF0TMB3IC0_F0TG_MB_C_brd_V02_OCP.brd")
		(comment 1 "Grand Teton / footprints 3664-3666 of 8354")
	)
	(layers
		(0 "F.Cu" signal "TOP")
		(4 "In1.Cu" signal "GND")
		(6 "In2.Cu" signal "IN1")
		(8 "In3.Cu" signal "GND1")
		(10 "In4.Cu" signal "IN2")
		(12 "In5.Cu" signal "GND2")
		(14 "In6.Cu" signal "IN3")
		(16 "In7.Cu" signal "GND3")
		(18 "In8.Cu" signal "VCC")
		(20 "In9.Cu" signal "VCC1")
		(22 "In10.Cu" signal "GND4")
		(24 "In11.Cu" signal "IN4")
		(26 "In12.Cu" signal "GND5")
		(28 "In13.Cu" signal "IN5")
		(30 "In14.Cu" signal "GND6")
		(32 "In15.Cu" signal "IN6")
		(34 "In16.Cu" signal "GND7")
		(2 "B.Cu" signal "BOTTOM")
		(9 "F.Adhes" user "F.Adhesive")
		(11 "B.Adhes" user "B.Adhesive")
		(13 "F.Paste" user "Package Geometry/Pastemask Top")
		(15 "B.Paste" user "Package Geometry/Pastemask Bottom")
		(5 "F.SilkS" user "Ref Des/Silkscreen Top")
		(7 "B.SilkS" user "Ref Des/Silkscreen Bottom")
		(1 "F.Mask" user "Board Geometry/Soldermask Top")
		(3 "B.Mask" user "Board Geometry/Soldermask Bottom")
		(17 "Dwgs.User" user "User.Drawings")
		(19 "Cmts.User" user "User.Comments")
		(21 "Eco1.User" user "User.Eco1")
		(23 "Eco2.User" user "User.Eco2")
		(25 "Edge.Cuts" user "Board Geometry/Outline")
		(27 "Margin" user)
		(31 "F.CrtYd" user "Package Geometry/Place Bound Top")
		(29 "B.CrtYd" user "Package Geometry/Place Bound Bottom")
		(35 "F.Fab" user "Ref Des/Assembly Top")
		(33 "B.Fab" user "Ref Des/Assembly Bottom")
	)
	(footprint ""
		(layer "F.Cu")
		(at 442.18352 -434.549296)
		(property "Reference" "Q106"
			(at -1.499616 -2.115566 0)
			(unlocked yes)
			(layer "F.SilkS")
			(effects
				(font
					(size 0.7874 0.5842)
					(thickness 0.1524)
				)
				(justify left)
			)
		)
		(property "Value" ""
			(at 0 0 0)
			(layer "F.Fab")
			(effects
				(font
					(size 1.27 1.27)
				)
			)
		)
		(duplicate_pad_numbers_are_jumpers no)
		(fp_line
			(start -1.332738 -1.100074)
			(end -0.4826 -1.100074)
			(stroke
				(width 0.1524)
				(type default)
			)
			(layer "F.SilkS")
		)
		(fp_line
			(start -1.332738 1.100074)
			(end -1.332738 -1.100074)
			(stroke
				(width 0.1524)
				(type default)
			)
			(layer "F.SilkS")
		)
		(fp_line
			(start -0.4826 -1.100074)
			(end 0 -0.541274)
			(stroke
				(width 0.1524)
				(type default)
			)
			(layer "F.SilkS")
		)
		(fp_line
			(start 0 -0.541274)
			(end 0.4826 -1.100074)
			(stroke
				(width 0.1524)
				(type default)
			)
			(layer "F.SilkS")
		)
		(fp_line
			(start 0.4826 -1.100074)
			(end 1.332738 -1.100074)
			(stroke
				(width 0.1524)
				(type default)
			)
			(layer "F.SilkS")
		)
		(fp_line
			(start 1.332738 -1.100074)
			(end 1.332738 1.100074)
			(stroke
				(width 0.1524)
				(type default)
			)
			(layer "F.SilkS")
		)
		(fp_line
			(start 1.332738 1.100074)
			(end -1.332738 1.100074)
			(stroke
				(width 0.1524)
				(type default)
			)
			(layer "F.SilkS")
		)
		(fp_poly
			(pts
				(xy -1.533144 -0.649986) (xy -2.2352 -0.298958) (xy -2.2352 -1.001014)
			)
			(stroke
				(width 0)
				(type default)
			)
			(fill yes)
			(layer "F.SilkS")
		)
		(fp_line
			(start -0.674878 -1.100074)
			(end 0.674878 -1.100074)
			(stroke
				(width 0.1)
				(type default)
			)
			(layer "F.Fab")
		)
		(fp_line
			(start -0.674878 1.100074)
			(end -0.674878 -1.100074)
			(stroke
				(width 0.1)
				(type default)
			)
			(layer "F.Fab")
		)
		(fp_line
			(start 0.674878 -1.100074)
			(end 0.674878 1.100074)
			(stroke
				(width 0.1)
				(type default)
			)
			(layer "F.Fab")
		)
		(fp_line
			(start 0.674878 1.100074)
			(end -0.674878 1.100074)
			(stroke
				(width 0.1)
				(type default)
			)
			(layer "F.Fab")
		)
		(fp_poly
			(pts
				(xy -2.2352 -0.298958) (xy -2.2352 -1.001014) (xy -1.533144 -0.649986)
			)
			(stroke
				(width 0)
				(type default)
			)
			(fill yes)
			(layer "F.Fab")
		)
		(pad "1" smd rect
			(at -0.94996 -0.649986 90)
			(size 0.4318 0.508)
			(layers "F.Cu" "F.Mask" "F.Paste")
			(net "GND")
		)
		(pad "2" smd rect
			(at -0.94996 0 90)
			(size 0.4318 0.508)
			(layers "F.Cu" "F.Mask" "F.Paste")
			(net "GPU_WP_HW_CTRL_N")
		)
		(pad "3" smd rect
			(at -0.94996 0.649986 90)
			(size 0.4318 0.508)
			(layers "F.Cu" "F.Mask" "F.Paste")
			(net "GPU_WP_HW_CTRL_ISO_N")
		)
		(pad "4" smd rect
			(at 0.94996 0.649986 90)
			(size 0.4318 0.508)
			(layers "F.Cu" "F.Mask" "F.Paste")
			(net "GND")
		)
		(pad "5" smd rect
			(at 0.94996 0 90)
			(size 0.4318 0.508)
			(layers "F.Cu" "F.Mask" "F.Paste")
			(net "GPU_WP_HW_CTRL_ISO")
		)
		(pad "6" smd rect
			(at 0.94996 -0.649986 90)
			(size 0.4318 0.508)
			(layers "F.Cu" "F.Mask" "F.Paste")
			(net "GPU_WP_HW_CTRL_ISO")
		)
	)
	(footprint ""
		(layer "F.Cu")
		(at 93.717364 -408.517344 -90)
		(property "Reference" "C6660"
			(at 0 0 270)
			(layer "F.SilkS")
			(hide yes)
			(effects
				(font
					(size 1.27 1.27)
				)
			)
		)
		(property "Value" ""
			(at 0 0 270)
			(layer "F.Fab")
			(effects
				(font
					(size 1.27 1.27)
				)
			)
		)
		(duplicate_pad_numbers_are_jumpers no)
		(fp_line
			(start -0.299974 0.150114)
			(end -0.299974 -0.150114)
			(stroke
				(width 0.1)
				(type default)
			)
			(layer "F.Fab")
		)
		(fp_line
			(start 0.299974 0.150114)
			(end -0.299974 0.150114)
			(stroke
				(width 0.1)
				(type default)
			)
			(layer "F.Fab")
		)
		(fp_line
			(start -0.299974 -0.150114)
			(end 0.299974 -0.150114)
			(stroke
				(width 0.1)
				(type default)
			)
			(layer "F.Fab")
		)
		(fp_line
			(start 0.299974 -0.150114)
			(end 0.299974 0.150114)
			(stroke
				(width 0.1)
				(type default)
			)
			(layer "F.Fab")
		)
		(pad "1" smd rect
			(at -0.2667 0 270)
			(size 0.3048 0.381)
			(layers "F.Cu" "F.Mask" "F.Paste")
			(net "P5E_CPU1_P0_TX_BUF_C_DN<15>")
		)
		(pad "2" smd rect
			(at 0.2667 0 270)
			(size 0.3048 0.381)
			(layers "F.Cu" "F.Mask" "F.Paste")
			(net "P5E_CPU1_P0_TX_BUF_DN<15>")
		)
	)
	(footprint ""
		(layer "F.Cu")
		(at 79.523844 -339.644736 90)
		(property "Reference" "PR259"
			(at 0 0 90)
			(layer "F.SilkS")
			(hide yes)
			(effects
				(font
					(size 1.27 1.27)
				)
			)
		)
		(property "Value" ""
			(at 0 0 90)
			(layer "F.Fab")
			(effects
				(font
					(size 1.27 1.27)
				)
			)
		)
		(duplicate_pad_numbers_are_jumpers no)
		(fp_line
			(start 0.7874 -0.4064)
			(end 0.7874 0.4064)
			(stroke
				(width 0.1524)
				(type default)
			)
			(layer "F.SilkS")
		)
		(fp_line
			(start -0.7874 -0.4064)
			(end 0.7874 -0.4064)
			(stroke
				(width 0.1524)
				(type default)
			)
			(layer "F.SilkS")
		)
		(fp_line
			(start 0.7874 0.4064)
			(end -0.7874 0.4064)
			(stroke
				(width 0.1524)
				(type default)
			)
			(layer "F.SilkS")
		)
		(fp_line
			(start -0.7874 0.4064)
			(end -0.7874 -0.4064)
			(stroke
				(width 0.1524)
				(type default)
			)
			(layer "F.SilkS")
		)
		(fp_line
			(start -0.12065 -0.305054)
			(end -0.12065 -0.2794)
			(stroke
				(width 0.1)
				(type default)
			)
			(layer "F.Fab")
		)
		(fp_line
			(start -0.67945 -0.305054)
			(end -0.12065 -0.305054)
			(stroke
				(width 0.1)
				(type default)
			)
			(layer "F.Fab")
		)
		(fp_line
			(start 0.67945 -0.3048)
			(end 0.67945 0.3048)
			(stroke
				(width 0.1)
				(type default)
			)
			(layer "F.Fab")
		)
		(fp_line
			(start 0.12065 -0.3048)
			(end 0.67945 -0.3048)
			(stroke
				(width 0.1)
				(type default)
			)
			(layer "F.Fab")
		)
		(fp_line
			(start 0.12065 -0.2794)
			(end 0.12065 -0.3048)
			(stroke
				(width 0.1)
				(type default)
			)
			(layer "F.Fab")
		)
		(fp_line
			(start -0.12065 -0.2794)
			(end 0.12065 -0.2794)
			(stroke
				(width 0.1)
				(type default)
			)
			(layer "F.Fab")
		)
		(fp_line
			(start 0.120396 0.2794)
			(end -0.12065 0.2794)
			(stroke
				(width 0.1)
				(type default)
			)
			(layer "F.Fab")
		)
		(fp_line
			(start -0.12065 0.2794)
			(end -0.12065 0.3048)
			(stroke
				(width 0.1)
				(type default)
			)
			(layer "F.Fab")
		)
		(fp_line
			(start 0.67945 0.3048)
			(end 0.120396 0.3048)
			(stroke
				(width 0.1)
				(type default)
			)
			(layer "F.Fab")
		)
		(fp_line
			(start 0.120396 0.3048)
			(end 0.120396 0.2794)
			(stroke
				(width 0.1)
				(type default)
			)
			(layer "F.Fab")
		)
		(fp_line
			(start -0.12065 0.3048)
			(end -0.67945 0.3048)
			(stroke
				(width 0.1)
				(type default)
			)
			(layer "F.Fab")
		)
		(fp_line
			(start -0.67945 0.3048)
			(end -0.67945 -0.305054)
			(stroke
				(width 0.1)
				(type default)
			)
			(layer "F.Fab")
		)
		(pad "1" smd circle
			(at -0.40005 0 90)
			(size 0 0)
			(layers "F.Cu" "F.Mask" "F.Paste")
			(net "SW_PVDDCR_CPU1_P1_BOOT2")
		)
		(pad "2" smd circle
			(at 0.40005 0 90)
			(size 0 0)
			(layers "F.Cu" "F.Mask" "F.Paste")
			(net "SW_PVDDCR_CPU1_P1_BOOT2_R")
		)
	)
)
